(kicad_pcb
	(version 20260206)
	(generator "pcbnew")
	(generator_version "10.0")
	(general
		(thickness 1.6)
		(legacy_teardrops no)
	)
	(paper "A4")
	(title_block
		(title "03242023_DA0F0TMBIJ0_F0T_Motherboard_J_brd_V01_OCP.brd")
		(comment 1 "Grand Teton / footprints 4342-4348 of 6105")
	)
	(layers
		(0 "F.Cu" signal "TOP")
		(4 "In1.Cu" signal "GND")
		(6 "In2.Cu" signal "IN1")
		(8 "In3.Cu" signal "GND1")
		(10 "In4.Cu" signal "IN2")
		(12 "In5.Cu" signal "GND2")
		(14 "In6.Cu" signal "IN3")
		(16 "In7.Cu" signal "GND3")
		(18 "In8.Cu" signal "VCC")
		(20 "In9.Cu" signal "VCC1")
		(22 "In10.Cu" signal "GND4")
		(24 "In11.Cu" signal "IN4")
		(26 "In12.Cu" signal "GND5")
		(28 "In13.Cu" signal "IN5")
		(30 "In14.Cu" signal "GND6")
		(32 "In15.Cu" signal "IN6")
		(34 "In16.Cu" signal "GND7")
		(2 "B.Cu" signal "BOTTOM")
		(9 "F.Adhes" user "F.Adhesive")
		(11 "B.Adhes" user "B.Adhesive")
		(13 "F.Paste" user "Package Geometry/Pastemask Top")
		(15 "B.Paste" user "Package Geometry/Pastemask Bottom")
		(5 "F.SilkS" user "Ref Des/Silkscreen Top")
		(7 "B.SilkS" user "Ref Des/Silkscreen Bottom")
		(1 "F.Mask" user "Board Geometry/Soldermask Top")
		(3 "B.Mask" user "Board Geometry/Soldermask Bottom")
		(17 "Dwgs.User" user "User.Drawings")
		(19 "Cmts.User" user "User.Comments")
		(21 "Eco1.User" user "User.Eco1")
		(23 "Eco2.User" user "User.Eco2")
		(25 "Edge.Cuts" user "Board Geometry/Outline")
		(27 "Margin" user)
		(31 "F.CrtYd" user "Package Geometry/Place Bound Top")
		(29 "B.CrtYd" user "Package Geometry/Place Bound Bottom")
		(35 "F.Fab" user "Ref Des/Assembly Top")
		(33 "B.Fab" user "Ref Des/Assembly Bottom")
	)
	(footprint ""
		(layer "B.Cu")
		(at 17.725136 -192.848484)
		(property "Reference" "R963"
			(at 0 0 0)
			(layer "B.SilkS")
			(hide yes)
			(effects
				(font
					(size 1.27 1.27)
				)
				(justify mirror)
			)
		)
		(property "Value" ""
			(at 0 0 0)
			(layer "B.Fab")
			(effects
				(font
					(size 1.27 1.27)
				)
				(justify mirror)
			)
		)
		(duplicate_pad_numbers_are_jumpers no)
		(fp_line
			(start -0.7874 -0.4064)
			(end -0.7874 0.4064)
			(stroke
				(width 0.1524)
				(type default)
			)
			(layer "B.SilkS")
		)
		(fp_line
			(start -0.7874 0.4064)
			(end 0.7874 0.4064)
			(stroke
				(width 0.1524)
				(type default)
			)
			(layer "B.SilkS")
		)
		(fp_line
			(start 0.7874 -0.4064)
			(end -0.7874 -0.4064)
			(stroke
				(width 0.1524)
				(type default)
			)
			(layer "B.SilkS")
		)
		(fp_line
			(start 0.7874 0.4064)
			(end 0.7874 -0.4064)
			(stroke
				(width 0.1524)
				(type default)
			)
			(layer "B.SilkS")
		)
		(fp_line
			(start -0.67945 -0.3048)
			(end -0.67945 0.3048)
			(stroke
				(width 0.1)
				(type default)
			)
			(layer "B.Fab")
		)
		(fp_line
			(start -0.67945 0.3048)
			(end -0.120396 0.3048)
			(stroke
				(width 0.1)
				(type default)
			)
			(layer "B.Fab")
		)
		(fp_line
			(start -0.12065 -0.3048)
			(end -0.67945 -0.3048)
			(stroke
				(width 0.1)
				(type default)
			)
			(layer "B.Fab")
		)
		(fp_line
			(start -0.12065 -0.2794)
			(end -0.12065 -0.3048)
			(stroke
				(width 0.1)
				(type default)
			)
			(layer "B.Fab")
		)
		(fp_line
			(start -0.120396 0.2794)
			(end 0.12065 0.2794)
			(stroke
				(width 0.1)
				(type default)
			)
			(layer "B.Fab")
		)
		(fp_line
			(start -0.120396 0.3048)
			(end -0.120396 0.2794)
			(stroke
				(width 0.1)
				(type default)
			)
			(layer "B.Fab")
		)
		(fp_line
			(start 0.12065 -0.305054)
			(end 0.12065 -0.2794)
			(stroke
				(width 0.1)
				(type default)
			)
			(layer "B.Fab")
		)
		(fp_line
			(start 0.12065 -0.2794)
			(end -0.12065 -0.2794)
			(stroke
				(width 0.1)
				(type default)
			)
			(layer "B.Fab")
		)
		(fp_line
			(start 0.12065 0.2794)
			(end 0.12065 0.3048)
			(stroke
				(width 0.1)
				(type default)
			)
			(layer "B.Fab")
		)
		(fp_line
			(start 0.12065 0.3048)
			(end 0.67945 0.3048)
			(stroke
				(width 0.1)
				(type default)
			)
			(layer "B.Fab")
		)
		(fp_line
			(start 0.67945 -0.305054)
			(end 0.12065 -0.305054)
			(stroke
				(width 0.1)
				(type default)
			)
			(layer "B.Fab")
		)
		(fp_line
			(start 0.67945 0.3048)
			(end 0.67945 -0.305054)
			(stroke
				(width 0.1)
				(type default)
			)
			(layer "B.Fab")
		)
		(pad "1" smd circle
			(at 0.40005 0 180)
			(size 0 0)
			(layers "B.Cu" "B.Mask" "B.Paste")
			(net "PVNN_TERM_CPU1")
		)
		(pad "2" smd circle
			(at -0.40005 0 180)
			(size 0 0)
			(layers "B.Cu" "B.Mask" "B.Paste")
			(net "SMB_PEHPCPU1_GTL_R_SCL")
		)
	)
	(footprint ""
		(layer "B.Cu")
		(at 421.138604 -353.117404 -90)
		(property "Reference" "PC612_P0_1"
			(at 0 0 90)
			(layer "B.SilkS")
			(hide yes)
			(effects
				(font
					(size 1.27 1.27)
				)
				(justify mirror)
			)
		)
		(property "Value" ""
			(at 0 0 90)
			(layer "B.Fab")
			(effects
				(font
					(size 1.27 1.27)
				)
				(justify mirror)
			)
		)
		(duplicate_pad_numbers_are_jumpers no)
		(fp_line
			(start -0.7874 0.4064)
			(end 0.7874 0.4064)
			(stroke
				(width 0.1524)
				(type default)
			)
			(layer "B.SilkS")
		)
		(fp_line
			(start 0.7874 0.4064)
			(end 0.7874 -0.4064)
			(stroke
				(width 0.1524)
				(type default)
			)
			(layer "B.SilkS")
		)
		(fp_line
			(start -0.7874 -0.4064)
			(end -0.7874 0.4064)
			(stroke
				(width 0.1524)
				(type default)
			)
			(layer "B.SilkS")
		)
		(fp_line
			(start 0.7874 -0.4064)
			(end -0.7874 -0.4064)
			(stroke
				(width 0.1524)
				(type default)
			)
			(layer "B.SilkS")
		)
		(fp_line
			(start -0.67945 0.3048)
			(end -0.120396 0.3048)
			(stroke
				(width 0.1)
				(type default)
			)
			(layer "B.Fab")
		)
		(fp_line
			(start -0.120396 0.3048)
			(end -0.120396 0.2794)
			(stroke
				(width 0.1)
				(type default)
			)
			(layer "B.Fab")
		)
		(fp_line
			(start 0.12065 0.3048)
			(end 0.67945 0.3048)
			(stroke
				(width 0.1)
				(type default)
			)
			(layer "B.Fab")
		)
		(fp_line
			(start 0.67945 0.3048)
			(end 0.67945 -0.305054)
			(stroke
				(width 0.1)
				(type default)
			)
			(layer "B.Fab")
		)
		(fp_line
			(start -0.120396 0.2794)
			(end 0.12065 0.2794)
			(stroke
				(width 0.1)
				(type default)
			)
			(layer "B.Fab")
		)
		(fp_line
			(start 0.12065 0.2794)
			(end 0.12065 0.3048)
			(stroke
				(width 0.1)
				(type default)
			)
			(layer "B.Fab")
		)
		(fp_line
			(start -0.12065 -0.2794)
			(end -0.12065 -0.3048)
			(stroke
				(width 0.1)
				(type default)
			)
			(layer "B.Fab")
		)
		(fp_line
			(start 0.12065 -0.2794)
			(end -0.12065 -0.2794)
			(stroke
				(width 0.1)
				(type default)
			)
			(layer "B.Fab")
		)
		(fp_line
			(start -0.67945 -0.3048)
			(end -0.67945 0.3048)
			(stroke
				(width 0.1)
				(type default)
			)
			(layer "B.Fab")
		)
		(fp_line
			(start -0.12065 -0.3048)
			(end -0.67945 -0.3048)
			(stroke
				(width 0.1)
				(type default)
			)
			(layer "B.Fab")
		)
		(fp_line
			(start 0.12065 -0.305054)
			(end 0.12065 -0.2794)
			(stroke
				(width 0.1)
				(type default)
			)
			(layer "B.Fab")
		)
		(fp_line
			(start 0.67945 -0.305054)
			(end 0.12065 -0.305054)
			(stroke
				(width 0.1)
				(type default)
			)
			(layer "B.Fab")
		)
		(pad "1" smd circle
			(at 0.40005 0 90)
			(size 0 0)
			(layers "B.Cu" "B.Mask" "B.Paste")
			(net "PVCCFA_EHV_FIVRA_CPU0")
		)
		(pad "2" smd circle
			(at -0.40005 0 90)
			(size 0 0)
			(layers "B.Cu" "B.Mask" "B.Paste")
			(net "GND")
		)
	)
	(footprint ""
		(layer "B.Cu")
		(at 86.473284 -190.705232 -90)
		(property "Reference" "R66"
			(at 0 0 90)
			(layer "B.SilkS")
			(hide yes)
			(effects
				(font
					(size 1.27 1.27)
				)
				(justify mirror)
			)
		)
		(property "Value" ""
			(at 0 0 90)
			(layer "B.Fab")
			(effects
				(font
					(size 1.27 1.27)
				)
				(justify mirror)
			)
		)
		(duplicate_pad_numbers_are_jumpers no)
		(fp_line
			(start -0.7874 0.4064)
			(end 0.7874 0.4064)
			(stroke
				(width 0.1524)
				(type default)
			)
			(layer "B.SilkS")
		)
		(fp_line
			(start 0.7874 0.4064)
			(end 0.7874 -0.4064)
			(stroke
				(width 0.1524)
				(type default)
			)
			(layer "B.SilkS")
		)
		(fp_line
			(start -0.7874 -0.4064)
			(end -0.7874 0.4064)
			(stroke
				(width 0.1524)
				(type default)
			)
			(layer "B.SilkS")
		)
		(fp_line
			(start 0.7874 -0.4064)
			(end -0.7874 -0.4064)
			(stroke
				(width 0.1524)
				(type default)
			)
			(layer "B.SilkS")
		)
		(fp_line
			(start -0.67945 0.3048)
			(end -0.120396 0.3048)
			(stroke
				(width 0.1)
				(type default)
			)
			(layer "B.Fab")
		)
		(fp_line
			(start -0.120396 0.3048)
			(end -0.120396 0.2794)
			(stroke
				(width 0.1)
				(type default)
			)
			(layer "B.Fab")
		)
		(fp_line
			(start 0.12065 0.3048)
			(end 0.67945 0.3048)
			(stroke
				(width 0.1)
				(type default)
			)
			(layer "B.Fab")
		)
		(fp_line
			(start 0.67945 0.3048)
			(end 0.67945 -0.305054)
			(stroke
				(width 0.1)
				(type default)
			)
			(layer "B.Fab")
		)
		(fp_line
			(start -0.120396 0.2794)
			(end 0.12065 0.2794)
			(stroke
				(width 0.1)
				(type default)
			)
			(layer "B.Fab")
		)
		(fp_line
			(start 0.12065 0.2794)
			(end 0.12065 0.3048)
			(stroke
				(width 0.1)
				(type default)
			)
			(layer "B.Fab")
		)
		(fp_line
			(start -0.12065 -0.2794)
			(end -0.12065 -0.3048)
			(stroke
				(width 0.1)
				(type default)
			)
			(layer "B.Fab")
		)
		(fp_line
			(start 0.12065 -0.2794)
			(end -0.12065 -0.2794)
			(stroke
				(width 0.1)
				(type default)
			)
			(layer "B.Fab")
		)
		(fp_line
			(start -0.67945 -0.3048)
			(end -0.67945 0.3048)
			(stroke
				(width 0.1)
				(type default)
			)
			(layer "B.Fab")
		)
		(fp_line
			(start -0.12065 -0.3048)
			(end -0.67945 -0.3048)
			(stroke
				(width 0.1)
				(type default)
			)
			(layer "B.Fab")
		)
		(fp_line
			(start 0.12065 -0.305054)
			(end 0.12065 -0.2794)
			(stroke
				(width 0.1)
				(type default)
			)
			(layer "B.Fab")
		)
		(fp_line
			(start 0.67945 -0.305054)
			(end 0.12065 -0.305054)
			(stroke
				(width 0.1)
				(type default)
			)
			(layer "B.Fab")
		)
		(pad "1" smd circle
			(at 0.40005 0 90)
			(size 0 0)
			(layers "B.Cu" "B.Mask" "B.Paste")
			(net "JTAG_DBP_CPU_QS_GTL_TMS")
		)
		(pad "2" smd circle
			(at -0.40005 0 90)
			(size 0 0)
			(layers "B.Cu" "B.Mask" "B.Paste")
			(net "JTAG_DBP_CPU1_QS_GTL_R_TMS")
		)
	)
	(footprint ""
		(layer "B.Cu")
		(at 308.899814 -321.549776 -90)
		(property "Reference" "C7"
			(at 0 0 90)
			(layer "B.SilkS")
			(hide yes)
			(effects
				(font
					(size 1.27 1.27)
				)
				(justify mirror)
			)
		)
		(property "Value" ""
			(at 0 0 90)
			(layer "B.Fab")
			(effects
				(font
					(size 1.27 1.27)
				)
				(justify mirror)
			)
		)
		(duplicate_pad_numbers_are_jumpers no)
		(fp_line
			(start -1.524 0.762)
			(end 1.524 0.762)
			(stroke
				(width 0.1524)
				(type default)
			)
			(layer "B.SilkS")
		)
		(fp_line
			(start 1.524 0.762)
			(end 1.524 -0.762)
			(stroke
				(width 0.1524)
				(type default)
			)
			(layer "B.SilkS")
		)
		(fp_line
			(start -1.524 -0.762)
			(end -1.524 0.762)
			(stroke
				(width 0.1524)
				(type default)
			)
			(layer "B.SilkS")
		)
		(fp_line
			(start 1.524 -0.762)
			(end -1.524 -0.762)
			(stroke
				(width 0.1524)
				(type default)
			)
			(layer "B.SilkS")
		)
		(fp_line
			(start -1.1049 0.724916)
			(end -1.1049 -0.724916)
			(stroke
				(width 0.1)
				(type default)
			)
			(layer "B.Fab")
		)
		(fp_line
			(start 1.1049 0.724916)
			(end -1.1049 0.724916)
			(stroke
				(width 0.1)
				(type default)
			)
			(layer "B.Fab")
		)
		(fp_line
			(start -1.1049 -0.724916)
			(end 1.1049 -0.724916)
			(stroke
				(width 0.1)
				(type default)
			)
			(layer "B.Fab")
		)
		(fp_line
			(start 1.1049 -0.724916)
			(end 1.1049 0.724916)
			(stroke
				(width 0.1)
				(type default)
			)
			(layer "B.Fab")
		)
		(pad "1" smd rect
			(at 0.889 0 270)
			(size 1.016 1.27)
			(layers "B.Cu" "B.Mask" "B.Paste")
			(net "P12V_S3_AUX_CPU0_NVDIMM")
		)
		(pad "2" smd rect
			(at -0.889 0 270)
			(size 1.016 1.27)
			(layers "B.Cu" "B.Mask" "B.Paste")
			(net "GND")
		)
	)
	(footprint ""
		(layer "B.Cu")
		(at 284.075378 -318.376046 180)
		(property "Reference" "R2491"
			(at 0 0 0)
			(layer "B.SilkS")
			(hide yes)
			(effects
				(font
					(size 1.27 1.27)
				)
				(justify mirror)
			)
		)
		(property "Value" ""
			(at 0 0 0)
			(layer "B.Fab")
			(effects
				(font
					(size 1.27 1.27)
				)
				(justify mirror)
			)
		)
		(duplicate_pad_numbers_are_jumpers no)
		(fp_line
			(start 0.7874 0.4064)
			(end 0.7874 -0.4064)
			(stroke
				(width 0.1524)
				(type default)
			)
			(layer "B.SilkS")
		)
		(fp_line
			(start 0.7874 -0.4064)
			(end -0.7874 -0.4064)
			(stroke
				(width 0.1524)
				(type default)
			)
			(layer "B.SilkS")
		)
		(fp_line
			(start -0.7874 0.4064)
			(end 0.7874 0.4064)
			(stroke
				(width 0.1524)
				(type default)
			)
			(layer "B.SilkS")
		)
		(fp_line
			(start -0.7874 -0.4064)
			(end -0.7874 0.4064)
			(stroke
				(width 0.1524)
				(type default)
			)
			(layer "B.SilkS")
		)
		(fp_line
			(start 0.67945 0.3048)
			(end 0.67945 -0.305054)
			(stroke
				(width 0.1)
				(type default)
			)
			(layer "B.Fab")
		)
		(fp_line
			(start 0.67945 -0.305054)
			(end 0.12065 -0.305054)
			(stroke
				(width 0.1)
				(type default)
			)
			(layer "B.Fab")
		)
		(fp_line
			(start 0.12065 0.3048)
			(end 0.67945 0.3048)
			(stroke
				(width 0.1)
				(type default)
			)
			(layer "B.Fab")
		)
		(fp_line
			(start 0.12065 0.2794)
			(end 0.12065 0.3048)
			(stroke
				(width 0.1)
				(type default)
			)
			(layer "B.Fab")
		)
		(fp_line
			(start 0.12065 -0.2794)
			(end -0.12065 -0.2794)
			(stroke
				(width 0.1)
				(type default)
			)
			(layer "B.Fab")
		)
		(fp_line
			(start 0.12065 -0.305054)
			(end 0.12065 -0.2794)
			(stroke
				(width 0.1)
				(type default)
			)
			(layer "B.Fab")
		)
		(fp_line
			(start -0.120396 0.3048)
			(end -0.120396 0.2794)
			(stroke
				(width 0.1)
				(type default)
			)
			(layer "B.Fab")
		)
		(fp_line
			(start -0.120396 0.2794)
			(end 0.12065 0.2794)
			(stroke
				(width 0.1)
				(type default)
			)
			(layer "B.Fab")
		)
		(fp_line
			(start -0.12065 -0.2794)
			(end -0.12065 -0.3048)
			(stroke
				(width 0.1)
				(type default)
			)
			(layer "B.Fab")
		)
		(fp_line
			(start -0.12065 -0.3048)
			(end -0.67945 -0.3048)
			(stroke
				(width 0.1)
				(type default)
			)
			(layer "B.Fab")
		)
		(fp_line
			(start -0.67945 0.3048)
			(end -0.120396 0.3048)
			(stroke
				(width 0.1)
				(type default)
			)
			(layer "B.Fab")
		)
		(fp_line
			(start -0.67945 -0.3048)
			(end -0.67945 0.3048)
			(stroke
				(width 0.1)
				(type default)
			)
			(layer "B.Fab")
		)
		(pad "1" smd circle
			(at 0.40005 0)
			(size 0 0)
			(layers "B.Cu" "B.Mask" "B.Paste")
			(net "PWRGD_FAIL_CPU0_CD")
		)
		(pad "2" smd circle
			(at -0.40005 0)
			(size 0 0)
			(layers "B.Cu" "B.Mask" "B.Paste")
			(net "PWRGD_FAIL_CPU0_CD_R1")
		)
	)
	(footprint ""
		(layer "B.Cu")
		(at 54.880002 -157.599634 180)
		(property "Reference" "PC450_P1_1"
			(at 0 0 0)
			(layer "B.SilkS")
			(hide yes)
			(effects
				(font
					(size 1.27 1.27)
				)
				(justify mirror)
			)
		)
		(property "Value" ""
			(at 0 0 0)
			(layer "B.Fab")
			(effects
				(font
					(size 1.27 1.27)
				)
				(justify mirror)
			)
		)
		(duplicate_pad_numbers_are_jumpers no)
		(fp_line
			(start 1.524 0.762)
			(end 1.524 -0.762)
			(stroke
				(width 0.1524)
				(type default)
			)
			(layer "B.SilkS")
		)
		(fp_line
			(start 1.524 -0.762)
			(end -1.524 -0.762)
			(stroke
				(width 0.1524)
				(type default)
			)
			(layer "B.SilkS")
		)
		(fp_line
			(start -1.524 0.762)
			(end 1.524 0.762)
			(stroke
				(width 0.1524)
				(type default)
			)
			(layer "B.SilkS")
		)
		(fp_line
			(start -1.524 -0.762)
			(end -1.524 0.762)
			(stroke
				(width 0.1524)
				(type default)
			)
			(layer "B.SilkS")
		)
		(fp_line
			(start 1.1049 0.724916)
			(end -1.1049 0.724916)
			(stroke
				(width 0.1)
				(type default)
			)
			(layer "B.Fab")
		)
		(fp_line
			(start 1.1049 -0.724916)
			(end 1.1049 0.724916)
			(stroke
				(width 0.1)
				(type default)
			)
			(layer "B.Fab")
		)
		(fp_line
			(start -1.1049 0.724916)
			(end -1.1049 -0.724916)
			(stroke
				(width 0.1)
				(type default)
			)
			(layer "B.Fab")
		)
		(fp_line
			(start -1.1049 -0.724916)
			(end 1.1049 -0.724916)
			(stroke
				(width 0.1)
				(type default)
			)
			(layer "B.Fab")
		)
		(pad "1" smd rect
			(at 0.889 0 180)
			(size 1.016 1.27)
			(layers "B.Cu" "B.Mask" "B.Paste")
			(net "SW_P12V_PVCCINFAON_CPU1_FLT")
		)
		(pad "2" smd rect
			(at -0.889 0 180)
			(size 1.016 1.27)
			(layers "B.Cu" "B.Mask" "B.Paste")
			(net "GND")
		)
	)
	(footprint ""
		(layer "B.Cu")
		(at 54.880002 -166.235634 180)
		(property "Reference" "PC377"
			(at 0 0 0)
			(layer "B.SilkS")
			(hide yes)
			(effects
				(font
					(size 1.27 1.27)
				)
				(justify mirror)
			)
		)
		(property "Value" ""
			(at 0 0 0)
			(layer "B.Fab")
			(effects
				(font
					(size 1.27 1.27)
				)
				(justify mirror)
			)
		)
		(duplicate_pad_numbers_are_jumpers no)
		(fp_line
			(start 1.524 0.762)
			(end 1.524 -0.762)
			(stroke
				(width 0.1524)
				(type default)
			)
			(layer "B.SilkS")
		)
		(fp_line
			(start 1.524 -0.762)
			(end -1.524 -0.762)
			(stroke
				(width 0.1524)
				(type default)
			)
			(layer "B.SilkS")
		)
		(fp_line
			(start -1.524 0.762)
			(end 1.524 0.762)
			(stroke
				(width 0.1524)
				(type default)
			)
			(layer "B.SilkS")
		)
		(fp_line
			(start -1.524 -0.762)
			(end -1.524 0.762)
			(stroke
				(width 0.1524)
				(type default)
			)
			(layer "B.SilkS")
		)
		(fp_line
			(start 1.1049 0.724916)
			(end -1.1049 0.724916)
			(stroke
				(width 0.1)
				(type default)
			)
			(layer "B.Fab")
		)
		(fp_line
			(start 1.1049 -0.724916)
			(end 1.1049 0.724916)
			(stroke
				(width 0.1)
				(type default)
			)
			(layer "B.Fab")
		)
		(fp_line
			(start -1.1049 0.724916)
			(end -1.1049 -0.724916)
			(stroke
				(width 0.1)
				(type default)
			)
			(layer "B.Fab")
		)
		(fp_line
			(start -1.1049 -0.724916)
			(end 1.1049 -0.724916)
			(stroke
				(width 0.1)
				(type default)
			)
			(layer "B.Fab")
		)
		(pad "1" smd rect
			(at 0.889 0 180)
			(size 1.016 1.27)
			(layers "B.Cu" "B.Mask" "B.Paste")
			(net "SW_P12V_PVCCINFAON_CPU1_FLT")
		)
		(pad "2" smd rect
			(at -0.889 0 180)
			(size 1.016 1.27)
			(layers "B.Cu" "B.Mask" "B.Paste")
			(net "GND")
		)
	)
)
